(kicad_pcb
	(version 20260206)
	(generator "pcbnew")
	(generator_version "10.0")
	(general
		(thickness 1.6)
		(legacy_teardrops no)
	)
	(paper "A4")
	(title_block
		(title "Wiwynn_Tioga_Pass_MB.brd")
		(comment 1 "Tioga Pass / footprint 2254 of 4770 (U5D1), pads 912-1015 of 3647")
	)
	(layers
		(0 "F.Cu" signal "TOP")
		(4 "In1.Cu" signal "L2GND")
		(6 "In2.Cu" signal "L3")
		(8 "In3.Cu" signal "L4GND")
		(10 "In4.Cu" signal "L5")
		(12 "In5.Cu" signal "L6GND")
		(14 "In6.Cu" signal "L7VCC")
		(16 "In7.Cu" signal "L8VCC")
		(18 "In8.Cu" signal "L9GND")
		(20 "In9.Cu" signal "L10")
		(22 "In10.Cu" signal "L11GND")
		(24 "In11.Cu" signal "L12")
		(26 "In12.Cu" signal "L13GND")
		(2 "B.Cu" signal "BOTTOM")
		(9 "F.Adhes" user "F.Adhesive")
		(11 "B.Adhes" user "B.Adhesive")
		(13 "F.Paste" user "Package Geometry/Pastemask Top")
		(15 "B.Paste" user "Package Geometry/Pastemask Bottom")
		(5 "F.SilkS" user "Ref Des/Silkscreen Top")
		(7 "B.SilkS" user "Ref Des/Silkscreen Bottom")
		(1 "F.Mask" user "Board Geometry/Soldermask Top")
		(3 "B.Mask" user "Board Geometry/Soldermask Bottom")
		(17 "Dwgs.User" user "User.Drawings")
		(19 "Cmts.User" user "User.Comments")
		(21 "Eco1.User" user "User.Eco1")
		(23 "Eco2.User" user "User.Eco2")
		(25 "Edge.Cuts" user "Board Geometry/Outline")
		(27 "Margin" user)
		(31 "F.CrtYd" user "Package Geometry/Place Bound Top")
		(29 "B.CrtYd" user "Package Geometry/Place Bound Bottom")
		(35 "F.Fab" user "Ref Des/Assembly Top")
		(33 "B.Fab" user "Ref Des/Assembly Bottom")
	)
	(footprint ""
		(layer "F.Cu")
		(at 270.000222 -76.550012 180)
		(property "Reference" "U5D1"
			(at 19.124422 31.601918 0)
			(unlocked yes)
			(layer "F.SilkS")
			(effects
				(font
					(size 0.7874 0.5842)
					(thickness 0.1524)
				)
			)
		)
		(property "Value" ""
			(at 0 0 180)
			(layer "F.Fab")
			(effects
				(font
					(size 1.27 1.27)
				)
			)
		)
		(duplicate_pad_numbers_are_jumpers no)
		(pad "BF83" smd circle
			(at 34.675064 -4.614926)
			(size 0.4318 0.4318)
			(layers "F.Cu" "F.Mask" "F.Paste")
			(net "PVCCIN_CPU0")
		)
		(pad "BF85" smd custom
			(at 36.392104 -4.614926 270)
			(size 0.10795 0.10795)
			(layers "F.Cu" "F.Mask" "F.Paste")
			(net "PVCCIN_CPU0")
			(options
				(clearance outline)
				(anchor circle)
			)
			(primitives
				(gr_poly
					(pts
						(arc
							(start 0.2159 -0.0381)
							(mid 0 -0.254)
							(end -0.2159 -0.0381)
						)
						(arc
							(start -0.2159 0.0381)
							(mid 0 0.254)
							(end 0.2159 0.0381)
						)
					)
					(width 0)
					(fill yes)
				)
			)
		)
		(pad "BG4" smd circle
			(at -34.675064 -2.319274)
			(size 0.4318 0.4318)
			(layers "F.Cu" "F.Mask" "F.Paste")
			(net "UPI_CPU0_CPU1_P0P0_DN<0>")
		)
		(pad "BG6" smd circle
			(at -32.958024 -2.319274)
			(size 0.4318 0.4318)
			(layers "F.Cu" "F.Mask" "F.Paste")
			(net "GND")
		)
		(pad "BG8" smd circle
			(at -31.240984 -2.319274)
			(size 0.4318 0.4318)
			(layers "F.Cu" "F.Mask" "F.Paste")
			(net "GND")
		)
		(pad "BG10" smd circle
			(at -29.523944 -2.319274)
			(size 0.4318 0.4318)
			(layers "F.Cu" "F.Mask" "F.Paste")
			(net "GND")
		)
		(pad "BG12" smd circle
			(at -27.806904 -2.319274)
			(size 0.4318 0.4318)
			(layers "F.Cu" "F.Mask" "F.Paste")
			(net "PVCCMCP_CPU0")
		)
		(pad "BG14" smd circle
			(at -26.090118 -2.319274)
			(size 0.4318 0.4318)
			(layers "F.Cu" "F.Mask" "F.Paste")
			(net "PVCCMCP_CPU0")
		)
		(pad "BG16" smd circle
			(at -24.373078 -2.319274)
			(size 0.4318 0.4318)
			(layers "F.Cu" "F.Mask" "F.Paste")
			(net "CLK_156M_OSC_CPU0_HFI_DP")
		)
		(pad "BG18" smd circle
			(at -22.656038 -2.319274)
			(size 0.4318 0.4318)
			(layers "F.Cu" "F.Mask" "F.Paste")
			(net "TP_CPU0_RSVD_145")
		)
		(pad "BG20" smd circle
			(at -20.938998 -2.319274)
			(size 0.4318 0.4318)
			(layers "F.Cu" "F.Mask" "F.Paste")
			(net "TP_CPU0_RSVD_144")
		)
		(pad "BG22" smd circle
			(at -19.221958 -2.319274)
			(size 0.4318 0.4318)
			(layers "F.Cu" "F.Mask" "F.Paste")
			(net "GND")
		)
		(pad "BG24" smd circle
			(at -17.504918 -2.319274)
			(size 0.4318 0.4318)
			(layers "F.Cu" "F.Mask" "F.Paste")
			(net "GND")
		)
		(pad "BG26" smd circle
			(at -15.787878 -2.319274)
			(size 0.4318 0.4318)
			(layers "F.Cu" "F.Mask" "F.Paste")
			(net "PVCCIO_CPU0")
		)
		(pad "BG60" smd circle
			(at 14.929612 -4.119372)
			(size 0.508 0.508)
			(layers "F.Cu" "F.Mask" "F.Paste")
			(net "PVCCIN_CPU0")
		)
		(pad "BG62" smd circle
			(at 16.646398 -4.119372)
			(size 0.4318 0.4318)
			(layers "F.Cu" "F.Mask" "F.Paste")
			(net "PVCCIN_CPU0")
		)
		(pad "BG64" smd circle
			(at 18.363438 -4.119372)
			(size 0.4318 0.4318)
			(layers "F.Cu" "F.Mask" "F.Paste")
			(net "PVCCIN_CPU0")
		)
		(pad "BG66" smd circle
			(at 20.080478 -4.119372)
			(size 0.4318 0.4318)
			(layers "F.Cu" "F.Mask" "F.Paste")
			(net "PVCCIN_CPU0")
		)
		(pad "BG68" smd circle
			(at 21.797518 -4.119372)
			(size 0.4318 0.4318)
			(layers "F.Cu" "F.Mask" "F.Paste")
			(net "PVCCIN_CPU0")
		)
		(pad "BG70" smd circle
			(at 23.514558 -4.119372)
			(size 0.4318 0.4318)
			(layers "F.Cu" "F.Mask" "F.Paste")
			(net "PVCCIN_CPU0")
		)
		(pad "BG72" smd circle
			(at 25.231598 -4.119372)
			(size 0.4318 0.4318)
			(layers "F.Cu" "F.Mask" "F.Paste")
			(net "GND")
		)
		(pad "BG74" smd circle
			(at 26.948384 -4.119372)
			(size 0.4318 0.4318)
			(layers "F.Cu" "F.Mask" "F.Paste")
			(net "GND")
		)
		(pad "BG76" smd circle
			(at 28.665424 -4.119372)
			(size 0.4318 0.4318)
			(layers "F.Cu" "F.Mask" "F.Paste")
			(net "GND")
		)
		(pad "BG78" smd circle
			(at 30.382464 -4.119372)
			(size 0.4318 0.4318)
			(layers "F.Cu" "F.Mask" "F.Paste")
			(net "GND")
		)
		(pad "BG80" smd circle
			(at 32.099504 -4.119372)
			(size 0.4318 0.4318)
			(layers "F.Cu" "F.Mask" "F.Paste")
			(net "GND")
		)
		(pad "BG82" smd circle
			(at 33.816544 -4.119372)
			(size 0.4318 0.4318)
			(layers "F.Cu" "F.Mask" "F.Paste")
			(net "GND")
		)
		(pad "BG84" smd custom
			(at 35.533584 -4.119372 270)
			(size 0.10795 0.10795)
			(layers "F.Cu" "F.Mask" "F.Paste")
			(net "PVCCIN_CPU0")
			(options
				(clearance outline)
				(anchor circle)
			)
			(primitives
				(gr_poly
					(pts
						(arc
							(start 0.2159 -0.0381)
							(mid 0 -0.254)
							(end -0.2159 -0.0381)
						)
						(arc
							(start -0.2159 0.0381)
							(mid 0 0.254)
							(end 0.2159 0.0381)
						)
					)
					(width 0)
					(fill yes)
				)
			)
		)
		(pad "BH3" smd custom
			(at -35.533584 -1.824228 90)
			(size 0.10795 0.10795)
			(layers "F.Cu" "F.Mask" "F.Paste")
			(net "UPI_CPU0_CPU1_P0P0_DP<0>")
			(options
				(clearance outline)
				(anchor circle)
			)
			(primitives
				(gr_poly
					(pts
						(arc
							(start 0.2159 -0.0381)
							(mid 0 -0.254)
							(end -0.2159 -0.0381)
						)
						(arc
							(start -0.2159 0.0381)
							(mid 0 0.254)
							(end 0.2159 0.0381)
						)
					)
					(width 0)
					(fill yes)
				)
			)
		)
		(pad "BH5" smd circle
			(at -33.816544 -1.824228)
			(size 0.4318 0.4318)
			(layers "F.Cu" "F.Mask" "F.Paste")
			(net "VSENSE_PVCCIO_CPU0_SKT_VSEN")
		)
		(pad "BH7" smd circle
			(at -32.099504 -1.824228)
			(size 0.4318 0.4318)
			(layers "F.Cu" "F.Mask" "F.Paste")
			(net "GND")
		)
		(pad "BH9" smd circle
			(at -30.382464 -1.824228)
			(size 0.4318 0.4318)
			(layers "F.Cu" "F.Mask" "F.Paste")
			(net "GND")
		)
		(pad "BH11" smd circle
			(at -28.665424 -1.824228)
			(size 0.4318 0.4318)
			(layers "F.Cu" "F.Mask" "F.Paste")
			(net "GND")
		)
		(pad "BH13" smd circle
			(at -26.948384 -1.824228)
			(size 0.4318 0.4318)
			(layers "F.Cu" "F.Mask" "F.Paste")
			(net "PVCCMCP_CPU0")
		)
		(pad "BH15" smd circle
			(at -25.231598 -1.824228)
			(size 0.4318 0.4318)
			(layers "F.Cu" "F.Mask" "F.Paste")
			(net "GND")
		)
		(pad "BH17" smd circle
			(at -23.514558 -1.824228)
			(size 0.4318 0.4318)
			(layers "F.Cu" "F.Mask" "F.Paste")
			(net "GND")
		)
		(pad "BH19" smd circle
			(at -21.797518 -1.824228)
			(size 0.4318 0.4318)
			(layers "F.Cu" "F.Mask" "F.Paste")
			(net "PVCCMCP_CPU0")
		)
		(pad "BH21" smd circle
			(at -20.080478 -1.824228)
			(size 0.4318 0.4318)
			(layers "F.Cu" "F.Mask" "F.Paste")
			(net "GND")
		)
		(pad "BH23" smd circle
			(at -18.363438 -1.824228)
			(size 0.4318 0.4318)
			(layers "F.Cu" "F.Mask" "F.Paste")
			(net "SMB_HFI1_CPU0_LVC2_SDA")
		)
		(pad "BH25" smd circle
			(at -16.646398 -1.824228)
			(size 0.4318 0.4318)
			(layers "F.Cu" "F.Mask" "F.Paste")
			(net "PVCCIO_CPU0")
		)
		(pad "BH27" smd circle
			(at -14.929612 -1.824228)
			(size 0.4318 0.4318)
			(layers "F.Cu" "F.Mask" "F.Paste")
			(net "PVCCIO_CPU0")
		)
		(pad "BH61" smd circle
			(at 15.787878 -3.624326)
			(size 0.4318 0.4318)
			(layers "F.Cu" "F.Mask" "F.Paste")
			(net "PVCCIN_CPU0")
		)
		(pad "BH63" smd circle
			(at 17.504918 -3.624326)
			(size 0.4318 0.4318)
			(layers "F.Cu" "F.Mask" "F.Paste")
			(net "PVCCIN_CPU0")
		)
		(pad "BH65" smd circle
			(at 19.221958 -3.624326)
			(size 0.4318 0.4318)
			(layers "F.Cu" "F.Mask" "F.Paste")
			(net "PVCCIN_CPU0")
		)
		(pad "BH67" smd circle
			(at 20.938998 -3.624326)
			(size 0.4318 0.4318)
			(layers "F.Cu" "F.Mask" "F.Paste")
			(net "PVCCIN_CPU0")
		)
		(pad "BH69" smd circle
			(at 22.656038 -3.624326)
			(size 0.4318 0.4318)
			(layers "F.Cu" "F.Mask" "F.Paste")
			(net "PVCCIN_CPU0")
		)
		(pad "BH71" smd circle
			(at 24.373078 -3.624326)
			(size 0.4318 0.4318)
			(layers "F.Cu" "F.Mask" "F.Paste")
			(net "PVCCIN_CPU0")
		)
		(pad "BH73" smd circle
			(at 26.090118 -3.624326)
			(size 0.4318 0.4318)
			(layers "F.Cu" "F.Mask" "F.Paste")
			(net "PVCCIN_CPU0")
		)
		(pad "BH75" smd circle
			(at 27.806904 -3.624326)
			(size 0.4318 0.4318)
			(layers "F.Cu" "F.Mask" "F.Paste")
			(net "PVCCIN_CPU0")
		)
		(pad "BH77" smd circle
			(at 29.523944 -3.624326)
			(size 0.4318 0.4318)
			(layers "F.Cu" "F.Mask" "F.Paste")
			(net "PVCCIN_CPU0")
		)
		(pad "BH79" smd circle
			(at 31.240984 -3.624326)
			(size 0.4318 0.4318)
			(layers "F.Cu" "F.Mask" "F.Paste")
			(net "PVCCIN_CPU0")
		)
		(pad "BH81" smd circle
			(at 32.958024 -3.624326)
			(size 0.4318 0.4318)
			(layers "F.Cu" "F.Mask" "F.Paste")
			(net "PVCCIN_CPU0")
		)
		(pad "BH83" smd circle
			(at 34.675064 -3.624326)
			(size 0.4318 0.4318)
			(layers "F.Cu" "F.Mask" "F.Paste")
			(net "PVCCIN_CPU0")
		)
		(pad "BJ4" smd circle
			(at -34.675064 -1.328674)
			(size 0.4318 0.4318)
			(layers "F.Cu" "F.Mask" "F.Paste")
			(net "GND")
		)
		(pad "BJ6" smd circle
			(at -32.958024 -1.328674)
			(size 0.4318 0.4318)
			(layers "F.Cu" "F.Mask" "F.Paste")
			(net "GND")
		)
		(pad "BJ8" smd circle
			(at -31.240984 -1.328674)
			(size 0.4318 0.4318)
			(layers "F.Cu" "F.Mask" "F.Paste")
			(net "P3E_CPU0_PE2_SS_RXP<14>")
		)
		(pad "BJ10" smd circle
			(at -29.523944 -1.328674)
			(size 0.4318 0.4318)
			(layers "F.Cu" "F.Mask" "F.Paste")
			(net "P3E_CPU0_PE2_SS_RXP<15>")
		)
		(pad "BJ12" smd circle
			(at -27.806904 -1.328674)
			(size 0.4318 0.4318)
			(layers "F.Cu" "F.Mask" "F.Paste")
			(net "PVCCMCP_CPU0")
		)
		(pad "BJ14" smd circle
			(at -26.090118 -1.328674)
			(size 0.4318 0.4318)
			(layers "F.Cu" "F.Mask" "F.Paste")
			(net "PVCCMCP_CPU0")
		)
		(pad "BJ16" smd circle
			(at -24.373078 -1.328674)
			(size 0.4318 0.4318)
			(layers "F.Cu" "F.Mask" "F.Paste")
			(net "PVCCMCP_CPU0")
		)
		(pad "BJ18" smd circle
			(at -22.656038 -1.328674)
			(size 0.4318 0.4318)
			(layers "F.Cu" "F.Mask" "F.Paste")
			(net "PVCCMCP_CPU0")
		)
		(pad "BJ20" smd circle
			(at -20.938998 -1.328674)
			(size 0.4318 0.4318)
			(layers "F.Cu" "F.Mask" "F.Paste")
			(net "PVCCMCP_CPU0")
		)
		(pad "BJ22" smd circle
			(at -19.221958 -1.328674)
			(size 0.4318 0.4318)
			(layers "F.Cu" "F.Mask" "F.Paste")
			(net "SMB_HFI1_CPU0_LVC2_SCL")
		)
		(pad "BJ24" smd circle
			(at -17.504918 -1.328674)
			(size 0.4318 0.4318)
			(layers "F.Cu" "F.Mask" "F.Paste")
			(net "PVCCIO_CPU0")
		)
		(pad "BJ26" smd circle
			(at -15.787878 -1.328674)
			(size 0.4318 0.4318)
			(layers "F.Cu" "F.Mask" "F.Paste")
			(net "PVCCIO_CPU0")
		)
		(pad "BJ60" smd circle
			(at 14.929612 -3.128772)
			(size 0.508 0.508)
			(layers "F.Cu" "F.Mask" "F.Paste")
			(net "PVCCIN_CPU0")
		)
		(pad "BJ62" smd circle
			(at 16.646398 -3.128772)
			(size 0.4318 0.4318)
			(layers "F.Cu" "F.Mask" "F.Paste")
			(net "PVCCIN_CPU0")
		)
		(pad "BJ64" smd circle
			(at 18.363438 -3.128772)
			(size 0.4318 0.4318)
			(layers "F.Cu" "F.Mask" "F.Paste")
			(net "PVCCIN_CPU0")
		)
		(pad "BJ66" smd circle
			(at 20.080478 -3.128772)
			(size 0.4318 0.4318)
			(layers "F.Cu" "F.Mask" "F.Paste")
			(net "PVCCIN_CPU0")
		)
		(pad "BJ68" smd circle
			(at 21.797518 -3.128772)
			(size 0.4318 0.4318)
			(layers "F.Cu" "F.Mask" "F.Paste")
			(net "PVCCIN_CPU0")
		)
		(pad "BJ70" smd circle
			(at 23.514558 -3.128772)
			(size 0.4318 0.4318)
			(layers "F.Cu" "F.Mask" "F.Paste")
			(net "PVCCIN_CPU0")
		)
		(pad "BJ72" smd circle
			(at 25.231598 -3.128772)
			(size 0.4318 0.4318)
			(layers "F.Cu" "F.Mask" "F.Paste")
			(net "PVCCIN_CPU0")
		)
		(pad "BJ74" smd circle
			(at 26.948384 -3.128772)
			(size 0.4318 0.4318)
			(layers "F.Cu" "F.Mask" "F.Paste")
			(net "PVCCIN_CPU0")
		)
		(pad "BJ76" smd circle
			(at 28.665424 -3.128772)
			(size 0.4318 0.4318)
			(layers "F.Cu" "F.Mask" "F.Paste")
			(net "PVCCIN_CPU0")
		)
		(pad "BJ78" smd circle
			(at 30.382464 -3.128772)
			(size 0.4318 0.4318)
			(layers "F.Cu" "F.Mask" "F.Paste")
			(net "PVCCIN_CPU0")
		)
		(pad "BJ80" smd circle
			(at 32.099504 -3.128772)
			(size 0.4318 0.4318)
			(layers "F.Cu" "F.Mask" "F.Paste")
			(net "PVCCIN_CPU0")
		)
		(pad "BJ82" smd circle
			(at 33.816544 -3.128772)
			(size 0.4318 0.4318)
			(layers "F.Cu" "F.Mask" "F.Paste")
			(net "PVCCIN_CPU0")
		)
		(pad "BJ84" smd custom
			(at 35.533584 -3.128772 270)
			(size 0.10795 0.10795)
			(layers "F.Cu" "F.Mask" "F.Paste")
			(net "PVCCIN_CPU0")
			(options
				(clearance outline)
				(anchor circle)
			)
			(primitives
				(gr_poly
					(pts
						(arc
							(start 0.2159 -0.0381)
							(mid 0 -0.254)
							(end -0.2159 -0.0381)
						)
						(arc
							(start -0.2159 0.0381)
							(mid 0 0.254)
							(end 0.2159 0.0381)
						)
					)
					(width 0)
					(fill yes)
				)
			)
		)
		(pad "BK3" smd custom
			(at -35.533584 -0.833628 90)
			(size 0.10795 0.10795)
			(layers "F.Cu" "F.Mask" "F.Paste")
			(net "GND")
			(options
				(clearance outline)
				(anchor circle)
			)
			(primitives
				(gr_poly
					(pts
						(arc
							(start 0.2159 -0.0381)
							(mid 0 -0.254)
							(end -0.2159 -0.0381)
						)
						(arc
							(start -0.2159 0.0381)
							(mid 0 0.254)
							(end 0.2159 0.0381)
						)
					)
					(width 0)
					(fill yes)
				)
			)
		)
		(pad "BK5" smd circle
			(at -33.816544 -0.833628)
			(size 0.4318 0.4318)
			(layers "F.Cu" "F.Mask" "F.Paste")
			(net "P3E_CPU0_PE2_SS_TXP<15>")
		)
		(pad "BK7" smd circle
			(at -32.099504 -0.833628)
			(size 0.4318 0.4318)
			(layers "F.Cu" "F.Mask" "F.Paste")
			(net "GND")
		)
		(pad "BK9" smd circle
			(at -30.382464 -0.833628)
			(size 0.4318 0.4318)
			(layers "F.Cu" "F.Mask" "F.Paste")
			(net "P3E_CPU0_PE2_SS_RXN<15>")
		)
		(pad "BK11" smd circle
			(at -28.665424 -0.833628)
			(size 0.4318 0.4318)
			(layers "F.Cu" "F.Mask" "F.Paste")
			(net "GND")
		)
		(pad "BK13" smd circle
			(at -26.948384 -0.833628)
			(size 0.4318 0.4318)
			(layers "F.Cu" "F.Mask" "F.Paste")
			(net "PVCCMCP_CPU0")
		)
		(pad "BK15" smd circle
			(at -25.231598 -0.833628)
			(size 0.4318 0.4318)
			(layers "F.Cu" "F.Mask" "F.Paste")
			(net "PVCCMCP_CPU0")
		)
		(pad "BK17" smd circle
			(at -23.514558 -0.833628)
			(size 0.4318 0.4318)
			(layers "F.Cu" "F.Mask" "F.Paste")
			(net "PVCCMCP_CPU0")
		)
		(pad "BK19" smd circle
			(at -21.797518 -0.833628)
			(size 0.4318 0.4318)
			(layers "F.Cu" "F.Mask" "F.Paste")
			(net "GND")
		)
		(pad "BK21" smd circle
			(at -20.080478 -0.833628)
			(size 0.4318 0.4318)
			(layers "F.Cu" "F.Mask" "F.Paste")
			(net "LED_HFI0_CPU0_N")
		)
		(pad "BK23" smd circle
			(at -18.363438 -0.833628)
			(size 0.4318 0.4318)
			(layers "F.Cu" "F.Mask" "F.Paste")
			(net "RST_HFI1_CPU0_LVT2_N")
		)
		(pad "BK25" smd circle
			(at -16.646398 -0.833628)
			(size 0.4318 0.4318)
			(layers "F.Cu" "F.Mask" "F.Paste")
			(net "PVCCIO_CPU0")
		)
		(pad "BK27" smd circle
			(at -14.929612 -0.833628)
			(size 0.4318 0.4318)
			(layers "F.Cu" "F.Mask" "F.Paste")
			(net "PVCCIO_CPU0")
		)
		(pad "BK61" smd circle
			(at 15.787878 -2.633726)
			(size 0.4318 0.4318)
			(layers "F.Cu" "F.Mask" "F.Paste")
			(net "PVCCIN_CPU0")
		)
		(pad "BK63" smd circle
			(at 17.504918 -2.633726)
			(size 0.4318 0.4318)
			(layers "F.Cu" "F.Mask" "F.Paste")
			(net "PVCCIN_CPU0")
		)
		(pad "BK65" smd circle
			(at 19.221958 -2.633726)
			(size 0.4318 0.4318)
			(layers "F.Cu" "F.Mask" "F.Paste")
			(net "PVCCIN_CPU0")
		)
		(pad "BK67" smd circle
			(at 20.938998 -2.633726)
			(size 0.4318 0.4318)
			(layers "F.Cu" "F.Mask" "F.Paste")
			(net "PVCCIN_CPU0")
		)
		(pad "BK69" smd circle
			(at 22.656038 -2.633726)
			(size 0.4318 0.4318)
			(layers "F.Cu" "F.Mask" "F.Paste")
			(net "PVCCIN_CPU0")
		)
		(pad "BK71" smd circle
			(at 24.373078 -2.633726)
			(size 0.4318 0.4318)
			(layers "F.Cu" "F.Mask" "F.Paste")
			(net "PVCCIN_CPU0")
		)
		(pad "BK73" smd circle
			(at 26.090118 -2.633726)
			(size 0.4318 0.4318)
			(layers "F.Cu" "F.Mask" "F.Paste")
			(net "PVCCIN_CPU0")
		)
		(pad "BK75" smd circle
			(at 27.806904 -2.633726)
			(size 0.4318 0.4318)
			(layers "F.Cu" "F.Mask" "F.Paste")
			(net "PVCCIN_CPU0")
		)
		(pad "BK77" smd circle
			(at 29.523944 -2.633726)
			(size 0.4318 0.4318)
			(layers "F.Cu" "F.Mask" "F.Paste")
			(net "PVCCIN_CPU0")
		)
		(pad "BK79" smd circle
			(at 31.240984 -2.633726)
			(size 0.4318 0.4318)
			(layers "F.Cu" "F.Mask" "F.Paste")
			(net "PVCCIN_CPU0")
		)
		(pad "BK81" smd circle
			(at 32.958024 -2.633726)
			(size 0.4318 0.4318)
			(layers "F.Cu" "F.Mask" "F.Paste")
			(net "PVCCIN_CPU0")
		)
		(pad "BK83" smd circle
			(at 34.675064 -2.633726)
			(size 0.4318 0.4318)
			(layers "F.Cu" "F.Mask" "F.Paste")
			(net "PVCCIN_CPU0")
		)
		(pad "BL4" smd circle
			(at -34.675064 -0.338074)
			(size 0.4318 0.4318)
			(layers "F.Cu" "F.Mask" "F.Paste")
			(net "P3E_CPU0_PE2_SS_TXN<14>")
		)
		(pad "BL6" smd circle
			(at -32.958024 -0.338074)
			(size 0.4318 0.4318)
			(layers "F.Cu" "F.Mask" "F.Paste")
			(net "GND")
		)
	)
)
